(kicad_pcb
	(version 20260206)
	(generator "pcbnew")
	(generator_version "10.0")
	(general
		(thickness 1.6)
		(legacy_teardrops no)
	)
	(paper "A4")
	(title_block
		(title "01162023_DA0F0TEBIF0_F0T_Expander_BD_F_brd_V02_OCP.brd")
		(comment 1 "Grand Teton / footprints 4648-4656 of 9728")
	)
	(layers
		(0 "F.Cu" signal "TOP")
		(4 "In1.Cu" signal "GND")
		(6 "In2.Cu" signal "VCC")
		(8 "In3.Cu" signal "VCC1")
		(10 "In4.Cu" signal "GND1")
		(12 "In5.Cu" signal "IN1")
		(14 "In6.Cu" signal "GND2")
		(16 "In7.Cu" signal "IN2")
		(18 "In8.Cu" signal "GND3")
		(20 "In9.Cu" signal "IN3")
		(22 "In10.Cu" signal "GND4")
		(24 "In11.Cu" signal "IN4")
		(26 "In12.Cu" signal "GND5")
		(28 "In13.Cu" signal "IN5")
		(30 "In14.Cu" signal "GND6")
		(32 "In15.Cu" signal "IN6")
		(34 "In16.Cu" signal "GND7")
		(2 "B.Cu" signal "BOTTOM")
		(9 "F.Adhes" user "F.Adhesive")
		(11 "B.Adhes" user "B.Adhesive")
		(13 "F.Paste" user "Package Geometry/Pastemask Top")
		(15 "B.Paste" user "Package Geometry/Pastemask Bottom")
		(5 "F.SilkS" user "Ref Des/Silkscreen Top")
		(7 "B.SilkS" user "Ref Des/Silkscreen Bottom")
		(1 "F.Mask" user "Board Geometry/Soldermask Top")
		(3 "B.Mask" user "Board Geometry/Soldermask Bottom")
		(17 "Dwgs.User" user "User.Drawings")
		(19 "Cmts.User" user "User.Comments")
		(21 "Eco1.User" user "User.Eco1")
		(23 "Eco2.User" user "User.Eco2")
		(25 "Edge.Cuts" user "Board Geometry/Outline")
		(27 "Margin" user)
		(31 "F.CrtYd" user "Package Geometry/Place Bound Top")
		(29 "B.CrtYd" user "Package Geometry/Place Bound Bottom")
		(35 "F.Fab" user "Ref Des/Assembly Top")
		(33 "B.Fab" user "Ref Des/Assembly Bottom")
	)
	(footprint ""
		(layer "F.Cu")
		(at 12.433046 -210.875372 -90)
		(property "Reference" "C4415"
			(at 0 0 270)
			(layer "F.SilkS")
			(hide yes)
			(effects
				(font
					(size 1.27 1.27)
				)
			)
		)
		(property "Value" ""
			(at 0 0 270)
			(layer "F.Fab")
			(effects
				(font
					(size 1.27 1.27)
				)
			)
		)
		(duplicate_pad_numbers_are_jumpers no)
		(fp_line
			(start -1.524 0.762)
			(end -1.524 -0.762)
			(stroke
				(width 0.1524)
				(type default)
			)
			(layer "F.SilkS")
		)
		(fp_line
			(start 1.524 0.762)
			(end -1.524 0.762)
			(stroke
				(width 0.1524)
				(type default)
			)
			(layer "F.SilkS")
		)
		(fp_line
			(start -1.524 -0.762)
			(end 1.524 -0.762)
			(stroke
				(width 0.1524)
				(type default)
			)
			(layer "F.SilkS")
		)
		(fp_line
			(start 1.524 -0.762)
			(end 1.524 0.762)
			(stroke
				(width 0.1524)
				(type default)
			)
			(layer "F.SilkS")
		)
		(fp_line
			(start -1.1049 0.724916)
			(end 1.1049 0.724916)
			(stroke
				(width 0.1)
				(type default)
			)
			(layer "F.Fab")
		)
		(fp_line
			(start 1.1049 0.724916)
			(end 1.1049 -0.724916)
			(stroke
				(width 0.1)
				(type default)
			)
			(layer "F.Fab")
		)
		(fp_line
			(start -1.1049 -0.724916)
			(end -1.1049 0.724916)
			(stroke
				(width 0.1)
				(type default)
			)
			(layer "F.Fab")
		)
		(fp_line
			(start 1.1049 -0.724916)
			(end -1.1049 -0.724916)
			(stroke
				(width 0.1)
				(type default)
			)
			(layer "F.Fab")
		)
		(pad "1" smd rect
			(at -0.889 0 90)
			(size 1.016 1.27)
			(layers "F.Cu" "F.Mask" "F.Paste")
			(net "P3V3_AUX")
		)
		(pad "2" smd rect
			(at 0.889 0 90)
			(size 1.016 1.27)
			(layers "F.Cu" "F.Mask" "F.Paste")
			(net "GND")
		)
	)
	(footprint ""
		(layer "F.Cu")
		(at 416.402012 -343.952322 90)
		(property "Reference" "C821"
			(at 0 0 90)
			(layer "F.SilkS")
			(hide yes)
			(effects
				(font
					(size 1.27 1.27)
				)
			)
		)
		(property "Value" ""
			(at 0 0 90)
			(layer "F.Fab")
			(effects
				(font
					(size 1.27 1.27)
				)
			)
		)
		(duplicate_pad_numbers_are_jumpers no)
		(fp_line
			(start 0.299974 -0.150114)
			(end 0.299974 0.150114)
			(stroke
				(width 0.1)
				(type default)
			)
			(layer "F.Fab")
		)
		(fp_line
			(start -0.299974 -0.150114)
			(end 0.299974 -0.150114)
			(stroke
				(width 0.1)
				(type default)
			)
			(layer "F.Fab")
		)
		(fp_line
			(start 0.299974 0.150114)
			(end -0.299974 0.150114)
			(stroke
				(width 0.1)
				(type default)
			)
			(layer "F.Fab")
		)
		(fp_line
			(start -0.299974 0.150114)
			(end -0.299974 -0.150114)
			(stroke
				(width 0.1)
				(type default)
			)
			(layer "F.Fab")
		)
		(pad "1" smd rect
			(at -0.2667 0 90)
			(size 0.3048 0.381)
			(layers "F.Cu" "F.Mask" "F.Paste")
			(net "P5E_PEX3_STN7_TX_DN<114>")
		)
		(pad "2" smd rect
			(at 0.2667 0 90)
			(size 0.3048 0.381)
			(layers "F.Cu" "F.Mask" "F.Paste")
			(net "P5E_PEX3_STN7_TX_C_DN<114>")
		)
	)
	(footprint ""
		(layer "F.Cu")
		(at 155.380436 -100.203254)
		(property "Reference" "C275"
			(at 0 0 0)
			(layer "F.SilkS")
			(hide yes)
			(effects
				(font
					(size 1.27 1.27)
				)
			)
		)
		(property "Value" ""
			(at 0 0 0)
			(layer "F.Fab")
			(effects
				(font
					(size 1.27 1.27)
				)
			)
		)
		(duplicate_pad_numbers_are_jumpers no)
		(fp_line
			(start -0.299974 -0.150114)
			(end 0.299974 -0.150114)
			(stroke
				(width 0.1)
				(type default)
			)
			(layer "F.Fab")
		)
		(fp_line
			(start -0.299974 0.150114)
			(end -0.299974 -0.150114)
			(stroke
				(width 0.1)
				(type default)
			)
			(layer "F.Fab")
		)
		(fp_line
			(start 0.299974 -0.150114)
			(end 0.299974 0.150114)
			(stroke
				(width 0.1)
				(type default)
			)
			(layer "F.Fab")
		)
		(fp_line
			(start 0.299974 0.150114)
			(end -0.299974 0.150114)
			(stroke
				(width 0.1)
				(type default)
			)
			(layer "F.Fab")
		)
		(pad "1" smd rect
			(at -0.2667 0)
			(size 0.3048 0.381)
			(layers "F.Cu" "F.Mask" "F.Paste")
			(net "P5E_PEX1_STN1_TX_DN<16>")
		)
		(pad "2" smd rect
			(at 0.2667 0)
			(size 0.3048 0.381)
			(layers "F.Cu" "F.Mask" "F.Paste")
			(net "P5E_PEX1_STN1_TX_C_DN<16>")
		)
	)
	(footprint ""
		(layer "F.Cu")
		(at 64.455802 -350.098614 90)
		(property "Reference" "C131"
			(at 0 0 90)
			(layer "F.SilkS")
			(hide yes)
			(effects
				(font
					(size 1.27 1.27)
				)
			)
		)
		(property "Value" ""
			(at 0 0 90)
			(layer "F.Fab")
			(effects
				(font
					(size 1.27 1.27)
				)
			)
		)
		(duplicate_pad_numbers_are_jumpers no)
		(fp_line
			(start 0.299974 -0.150114)
			(end 0.299974 0.150114)
			(stroke
				(width 0.1)
				(type default)
			)
			(layer "F.Fab")
		)
		(fp_line
			(start -0.299974 -0.150114)
			(end 0.299974 -0.150114)
			(stroke
				(width 0.1)
				(type default)
			)
			(layer "F.Fab")
		)
		(fp_line
			(start 0.299974 0.150114)
			(end -0.299974 0.150114)
			(stroke
				(width 0.1)
				(type default)
			)
			(layer "F.Fab")
		)
		(fp_line
			(start -0.299974 0.150114)
			(end -0.299974 -0.150114)
			(stroke
				(width 0.1)
				(type default)
			)
			(layer "F.Fab")
		)
		(pad "1" smd rect
			(at -0.2667 0 90)
			(size 0.3048 0.381)
			(layers "F.Cu" "F.Mask" "F.Paste")
			(net "P5E_PEX0_STN6_TX_DP<110>")
		)
		(pad "2" smd rect
			(at 0.2667 0 90)
			(size 0.3048 0.381)
			(layers "F.Cu" "F.Mask" "F.Paste")
			(net "P5E_PEX0_STN6_TX_C_DP<110>")
		)
	)
	(footprint ""
		(layer "F.Cu")
		(at 292.410896 -61.386974)
		(property "Reference" "R4507"
			(at 0 0 0)
			(layer "F.SilkS")
			(hide yes)
			(effects
				(font
					(size 1.27 1.27)
				)
			)
		)
		(property "Value" ""
			(at 0 0 0)
			(layer "F.Fab")
			(effects
				(font
					(size 1.27 1.27)
				)
			)
		)
		(duplicate_pad_numbers_are_jumpers no)
		(fp_line
			(start -0.7874 -0.4064)
			(end 0.7874 -0.4064)
			(stroke
				(width 0.1524)
				(type default)
			)
			(layer "F.SilkS")
		)
		(fp_line
			(start -0.7874 0.4064)
			(end -0.7874 -0.4064)
			(stroke
				(width 0.1524)
				(type default)
			)
			(layer "F.SilkS")
		)
		(fp_line
			(start 0.7874 -0.4064)
			(end 0.7874 0.4064)
			(stroke
				(width 0.1524)
				(type default)
			)
			(layer "F.SilkS")
		)
		(fp_line
			(start 0.7874 0.4064)
			(end -0.7874 0.4064)
			(stroke
				(width 0.1524)
				(type default)
			)
			(layer "F.SilkS")
		)
		(fp_line
			(start -0.67945 -0.305054)
			(end -0.12065 -0.305054)
			(stroke
				(width 0.1)
				(type default)
			)
			(layer "F.Fab")
		)
		(fp_line
			(start -0.67945 0.3048)
			(end -0.67945 -0.305054)
			(stroke
				(width 0.1)
				(type default)
			)
			(layer "F.Fab")
		)
		(fp_line
			(start -0.12065 -0.305054)
			(end -0.12065 -0.2794)
			(stroke
				(width 0.1)
				(type default)
			)
			(layer "F.Fab")
		)
		(fp_line
			(start -0.12065 -0.2794)
			(end 0.12065 -0.2794)
			(stroke
				(width 0.1)
				(type default)
			)
			(layer "F.Fab")
		)
		(fp_line
			(start -0.12065 0.2794)
			(end -0.12065 0.3048)
			(stroke
				(width 0.1)
				(type default)
			)
			(layer "F.Fab")
		)
		(fp_line
			(start -0.12065 0.3048)
			(end -0.67945 0.3048)
			(stroke
				(width 0.1)
				(type default)
			)
			(layer "F.Fab")
		)
		(fp_line
			(start 0.120396 0.2794)
			(end -0.12065 0.2794)
			(stroke
				(width 0.1)
				(type default)
			)
			(layer "F.Fab")
		)
		(fp_line
			(start 0.120396 0.3048)
			(end 0.120396 0.2794)
			(stroke
				(width 0.1)
				(type default)
			)
			(layer "F.Fab")
		)
		(fp_line
			(start 0.12065 -0.3048)
			(end 0.67945 -0.3048)
			(stroke
				(width 0.1)
				(type default)
			)
			(layer "F.Fab")
		)
		(fp_line
			(start 0.12065 -0.2794)
			(end 0.12065 -0.3048)
			(stroke
				(width 0.1)
				(type default)
			)
			(layer "F.Fab")
		)
		(fp_line
			(start 0.67945 -0.3048)
			(end 0.67945 0.3048)
			(stroke
				(width 0.1)
				(type default)
			)
			(layer "F.Fab")
		)
		(fp_line
			(start 0.67945 0.3048)
			(end 0.120396 0.3048)
			(stroke
				(width 0.1)
				(type default)
			)
			(layer "F.Fab")
		)
		(pad "1" smd circle
			(at -0.40005 0)
			(size 0 0)
			(layers "F.Cu" "F.Mask" "F.Paste")
			(net "PWRGD_P3V3_SSD10")
		)
		(pad "2" smd circle
			(at 0.40005 0)
			(size 0 0)
			(layers "F.Cu" "F.Mask" "F.Paste")
			(net "PWRGD_P3V3_SSD10_R")
		)
	)
	(footprint ""
		(layer "F.Cu")
		(at 154.707844 -155.3464 180)
		(property "Reference" "R116"
			(at 0 0 180)
			(layer "F.SilkS")
			(hide yes)
			(effects
				(font
					(size 1.27 1.27)
				)
			)
		)
		(property "Value" ""
			(at 0 0 180)
			(layer "F.Fab")
			(effects
				(font
					(size 1.27 1.27)
				)
			)
		)
		(duplicate_pad_numbers_are_jumpers no)
		(fp_line
			(start 0.7874 0.4064)
			(end -0.7874 0.4064)
			(stroke
				(width 0.1524)
				(type default)
			)
			(layer "F.SilkS")
		)
		(fp_line
			(start 0.7874 -0.4064)
			(end 0.7874 0.4064)
			(stroke
				(width 0.1524)
				(type default)
			)
			(layer "F.SilkS")
		)
		(fp_line
			(start -0.7874 0.4064)
			(end -0.7874 -0.4064)
			(stroke
				(width 0.1524)
				(type default)
			)
			(layer "F.SilkS")
		)
		(fp_line
			(start -0.7874 -0.4064)
			(end 0.7874 -0.4064)
			(stroke
				(width 0.1524)
				(type default)
			)
			(layer "F.SilkS")
		)
		(fp_line
			(start 0.67945 0.3048)
			(end 0.120396 0.3048)
			(stroke
				(width 0.1)
				(type default)
			)
			(layer "F.Fab")
		)
		(fp_line
			(start 0.67945 -0.3048)
			(end 0.67945 0.3048)
			(stroke
				(width 0.1)
				(type default)
			)
			(layer "F.Fab")
		)
		(fp_line
			(start 0.12065 -0.2794)
			(end 0.12065 -0.3048)
			(stroke
				(width 0.1)
				(type default)
			)
			(layer "F.Fab")
		)
		(fp_line
			(start 0.12065 -0.3048)
			(end 0.67945 -0.3048)
			(stroke
				(width 0.1)
				(type default)
			)
			(layer "F.Fab")
		)
		(fp_line
			(start 0.120396 0.3048)
			(end 0.120396 0.2794)
			(stroke
				(width 0.1)
				(type default)
			)
			(layer "F.Fab")
		)
		(fp_line
			(start 0.120396 0.2794)
			(end -0.12065 0.2794)
			(stroke
				(width 0.1)
				(type default)
			)
			(layer "F.Fab")
		)
		(fp_line
			(start -0.12065 0.3048)
			(end -0.67945 0.3048)
			(stroke
				(width 0.1)
				(type default)
			)
			(layer "F.Fab")
		)
		(fp_line
			(start -0.12065 0.2794)
			(end -0.12065 0.3048)
			(stroke
				(width 0.1)
				(type default)
			)
			(layer "F.Fab")
		)
		(fp_line
			(start -0.12065 -0.2794)
			(end 0.12065 -0.2794)
			(stroke
				(width 0.1)
				(type default)
			)
			(layer "F.Fab")
		)
		(fp_line
			(start -0.12065 -0.305054)
			(end -0.12065 -0.2794)
			(stroke
				(width 0.1)
				(type default)
			)
			(layer "F.Fab")
		)
		(fp_line
			(start -0.67945 0.3048)
			(end -0.67945 -0.305054)
			(stroke
				(width 0.1)
				(type default)
			)
			(layer "F.Fab")
		)
		(fp_line
			(start -0.67945 -0.305054)
			(end -0.12065 -0.305054)
			(stroke
				(width 0.1)
				(type default)
			)
			(layer "F.Fab")
		)
		(pad "1" smd circle
			(at -0.40005 0 180)
			(size 0 0)
			(layers "F.Cu" "F.Mask" "F.Paste")
			(net "NIC2_CLK")
		)
		(pad "2" smd circle
			(at 0.40005 0 180)
			(size 0 0)
			(layers "F.Cu" "F.Mask" "F.Paste")
			(net "GND")
		)
	)
	(footprint ""
		(layer "F.Cu")
		(at 96.834198 -95.263716 -90)
		(property "Reference" "R4446"
			(at 0 0 270)
			(layer "F.SilkS")
			(hide yes)
			(effects
				(font
					(size 1.27 1.27)
				)
			)
		)
		(property "Value" ""
			(at 0 0 270)
			(layer "F.Fab")
			(effects
				(font
					(size 1.27 1.27)
				)
			)
		)
		(duplicate_pad_numbers_are_jumpers no)
		(fp_line
			(start -0.7874 0.4064)
			(end -0.7874 -0.4064)
			(stroke
				(width 0.1524)
				(type default)
			)
			(layer "F.SilkS")
		)
		(fp_line
			(start 0.7874 0.4064)
			(end -0.7874 0.4064)
			(stroke
				(width 0.1524)
				(type default)
			)
			(layer "F.SilkS")
		)
		(fp_line
			(start -0.7874 -0.4064)
			(end 0.7874 -0.4064)
			(stroke
				(width 0.1524)
				(type default)
			)
			(layer "F.SilkS")
		)
		(fp_line
			(start 0.7874 -0.4064)
			(end 0.7874 0.4064)
			(stroke
				(width 0.1524)
				(type default)
			)
			(layer "F.SilkS")
		)
		(fp_line
			(start -0.67945 0.3048)
			(end -0.67945 -0.305054)
			(stroke
				(width 0.1)
				(type default)
			)
			(layer "F.Fab")
		)
		(fp_line
			(start -0.12065 0.3048)
			(end -0.67945 0.3048)
			(stroke
				(width 0.1)
				(type default)
			)
			(layer "F.Fab")
		)
		(fp_line
			(start 0.120396 0.3048)
			(end 0.120396 0.2794)
			(stroke
				(width 0.1)
				(type default)
			)
			(layer "F.Fab")
		)
		(fp_line
			(start 0.67945 0.3048)
			(end 0.120396 0.3048)
			(stroke
				(width 0.1)
				(type default)
			)
			(layer "F.Fab")
		)
		(fp_line
			(start -0.12065 0.2794)
			(end -0.12065 0.3048)
			(stroke
				(width 0.1)
				(type default)
			)
			(layer "F.Fab")
		)
		(fp_line
			(start 0.120396 0.2794)
			(end -0.12065 0.2794)
			(stroke
				(width 0.1)
				(type default)
			)
			(layer "F.Fab")
		)
		(fp_line
			(start -0.12065 -0.2794)
			(end 0.12065 -0.2794)
			(stroke
				(width 0.1)
				(type default)
			)
			(layer "F.Fab")
		)
		(fp_line
			(start 0.12065 -0.2794)
			(end 0.12065 -0.3048)
			(stroke
				(width 0.1)
				(type default)
			)
			(layer "F.Fab")
		)
		(fp_line
			(start 0.12065 -0.3048)
			(end 0.67945 -0.3048)
			(stroke
				(width 0.1)
				(type default)
			)
			(layer "F.Fab")
		)
		(fp_line
			(start 0.67945 -0.3048)
			(end 0.67945 0.3048)
			(stroke
				(width 0.1)
				(type default)
			)
			(layer "F.Fab")
		)
		(fp_line
			(start -0.67945 -0.305054)
			(end -0.12065 -0.305054)
			(stroke
				(width 0.1)
				(type default)
			)
			(layer "F.Fab")
		)
		(fp_line
			(start -0.12065 -0.305054)
			(end -0.12065 -0.2794)
			(stroke
				(width 0.1)
				(type default)
			)
			(layer "F.Fab")
		)
		(pad "1" smd circle
			(at -0.40005 0 270)
			(size 0 0)
			(layers "F.Cu" "F.Mask" "F.Paste")
			(net "PWRGD_P12V_NIC1")
		)
		(pad "2" smd circle
			(at 0.40005 0 270)
			(size 0 0)
			(layers "F.Cu" "F.Mask" "F.Paste")
			(net "PWRGD_P12V_NIC1_R")
		)
	)
	(footprint ""
		(layer "F.Cu")
		(at 469.009984 -551.319192 180)
		(property "Reference" "SCREW_SSD8_2"
			(at -5.207 -1.402334 0)
			(unlocked yes)
			(layer "B.SilkS")
			(effects
				(font
					(size 0.7874 0.5842)
					(thickness 0.1524)
				)
				(justify mirror)
			)
		)
		(property "Value" ""
			(at 0 0 180)
			(layer "F.Fab")
			(effects
				(font
					(size 1.27 1.27)
				)
			)
		)
		(duplicate_pad_numbers_are_jumpers no)
		(pad "1" thru_hole circle
			(at 0 0 180)
			(size 0.4572 0.4572)
			(drill 0.2032)
			(layers "*.Cu" "*.Mask")
			(remove_unused_layers no)
			(net "Net_9127")
			(clearance 0.127)
			(thermal_gap 0.127)
			(padstack
				(mode front_inner_back)
				(layer "Inner"
					(shape circle)
					(size 0.4572 0.4572)
					(clearance 0.127)
				)
				(layer "B.Cu"
					(shape circle)
					(size 0.508 0.508)
					(clearance 0.1016)
				)
			)
		)
	)
	(footprint ""
		(layer "F.Cu")
		(at 7.613396 -139.376404)
		(property "Reference" "R853"
			(at 0 0 0)
			(layer "F.SilkS")
			(hide yes)
			(effects
				(font
					(size 1.27 1.27)
				)
			)
		)
		(property "Value" ""
			(at 0 0 0)
			(layer "F.Fab")
			(effects
				(font
					(size 1.27 1.27)
				)
			)
		)
		(duplicate_pad_numbers_are_jumpers no)
		(fp_line
			(start -0.7874 -0.4064)
			(end 0.7874 -0.4064)
			(stroke
				(width 0.1524)
				(type default)
			)
			(layer "F.SilkS")
		)
		(fp_line
			(start -0.7874 0.4064)
			(end -0.7874 -0.4064)
			(stroke
				(width 0.1524)
				(type default)
			)
			(layer "F.SilkS")
		)
		(fp_line
			(start 0.7874 -0.4064)
			(end 0.7874 0.4064)
			(stroke
				(width 0.1524)
				(type default)
			)
			(layer "F.SilkS")
		)
		(fp_line
			(start 0.7874 0.4064)
			(end -0.7874 0.4064)
			(stroke
				(width 0.1524)
				(type default)
			)
			(layer "F.SilkS")
		)
		(fp_line
			(start -0.67945 -0.305054)
			(end -0.12065 -0.305054)
			(stroke
				(width 0.1)
				(type default)
			)
			(layer "F.Fab")
		)
		(fp_line
			(start -0.67945 0.3048)
			(end -0.67945 -0.305054)
			(stroke
				(width 0.1)
				(type default)
			)
			(layer "F.Fab")
		)
		(fp_line
			(start -0.12065 -0.305054)
			(end -0.12065 -0.2794)
			(stroke
				(width 0.1)
				(type default)
			)
			(layer "F.Fab")
		)
		(fp_line
			(start -0.12065 -0.2794)
			(end 0.12065 -0.2794)
			(stroke
				(width 0.1)
				(type default)
			)
			(layer "F.Fab")
		)
		(fp_line
			(start -0.12065 0.2794)
			(end -0.12065 0.3048)
			(stroke
				(width 0.1)
				(type default)
			)
			(layer "F.Fab")
		)
		(fp_line
			(start -0.12065 0.3048)
			(end -0.67945 0.3048)
			(stroke
				(width 0.1)
				(type default)
			)
			(layer "F.Fab")
		)
		(fp_line
			(start 0.120396 0.2794)
			(end -0.12065 0.2794)
			(stroke
				(width 0.1)
				(type default)
			)
			(layer "F.Fab")
		)
		(fp_line
			(start 0.120396 0.3048)
			(end 0.120396 0.2794)
			(stroke
				(width 0.1)
				(type default)
			)
			(layer "F.Fab")
		)
		(fp_line
			(start 0.12065 -0.3048)
			(end 0.67945 -0.3048)
			(stroke
				(width 0.1)
				(type default)
			)
			(layer "F.Fab")
		)
		(fp_line
			(start 0.12065 -0.2794)
			(end 0.12065 -0.3048)
			(stroke
				(width 0.1)
				(type default)
			)
			(layer "F.Fab")
		)
		(fp_line
			(start 0.67945 -0.3048)
			(end 0.67945 0.3048)
			(stroke
				(width 0.1)
				(type default)
			)
			(layer "F.Fab")
		)
		(fp_line
			(start 0.67945 0.3048)
			(end 0.120396 0.3048)
			(stroke
				(width 0.1)
				(type default)
			)
			(layer "F.Fab")
		)
		(pad "1" smd circle
			(at -0.40005 0)
			(size 0 0)
			(layers "F.Cu" "F.Mask" "F.Paste")
			(net "P3V3_AUX")
		)
		(pad "2" smd circle
			(at 0.40005 0)
			(size 0 0)
			(layers "F.Cu" "F.Mask" "F.Paste")
			(net "PWRGD_P12V_NIC0")
		)
	)
)
